(kicad_pcb
	(version 20260206)
	(generator "pcbnew")
	(generator_version "10.0")
	(general
		(thickness 1.6)
		(legacy_teardrops no)
	)
	(paper "A4")
	(title_block
		(title "panther-plus-userver — 13130-1b_20150205.brd")
		(comment 1 "Honey Badger (Wiwynn) / footprints 1023-1030 of 1509")
	)
	(layers
		(0 "F.Cu" signal "TOP")
		(4 "In1.Cu" signal "L2")
		(6 "In2.Cu" signal "L3")
		(8 "In3.Cu" signal "L4")
		(10 "In4.Cu" signal "L5")
		(12 "In5.Cu" signal "L6")
		(14 "In6.Cu" signal "L7")
		(16 "In7.Cu" signal "L8")
		(18 "In8.Cu" signal "L9")
		(20 "In9.Cu" signal "L10")
		(22 "In10.Cu" signal "L11")
		(2 "B.Cu" signal "BOTTOM")
		(9 "F.Adhes" user "F.Adhesive")
		(11 "B.Adhes" user "B.Adhesive")
		(13 "F.Paste" user "Package Geometry/Pastemask Top")
		(15 "B.Paste" user "Package Geometry/Pastemask Bottom")
		(5 "F.SilkS" user "Ref Des/Silkscreen Top")
		(7 "B.SilkS" user "Ref Des/Silkscreen Bottom")
		(1 "F.Mask" user "Board Geometry/Soldermask Top")
		(3 "B.Mask" user "Board Geometry/Soldermask Bottom")
		(17 "Dwgs.User" user "User.Drawings")
		(19 "Cmts.User" user "User.Comments")
		(21 "Eco1.User" user "User.Eco1")
		(23 "Eco2.User" user "User.Eco2")
		(25 "Edge.Cuts" user "Board Geometry/Outline")
		(27 "Margin" user)
		(31 "F.CrtYd" user "Package Geometry/Place Bound Top")
		(29 "B.CrtYd" user "Package Geometry/Place Bound Bottom")
		(35 "F.Fab" user "Ref Des/Assembly Top")
		(33 "B.Fab" user "Ref Des/Assembly Bottom")
	)
	(footprint ""
		(layer "B.Cu")
		(at 74.168 -45.085 90)
		(property "Reference" "R70"
			(at 0 0 90)
			(layer "B.SilkS")
			(hide yes)
			(effects
				(font
					(size 1.27 1.27)
				)
				(justify mirror)
			)
		)
		(property "Value" "4K7R2F-GP"
			(at -0.064008 -3.993896 90)
			(unlocked yes)
			(layer "B.Fab")
			(hide yes)
			(effects
				(font
					(size 1.016 1.016)
					(thickness 0.1524)
				)
				(justify mirror)
			)
		)
		(property "Device Type" "R402H16"
			(at -0.064008 -5.517896 90)
			(unlocked yes)
			(layer "B.Fab")
			(hide yes)
			(effects
				(font
					(size 1.016 1.016)
					(thickness 0.1524)
				)
				(justify mirror)
			)
		)
		(duplicate_pad_numbers_are_jumpers no)
		(fp_rect
			(start 0.381 0.8382)
			(end -0.381 -0.8382)
			(stroke
				(width 0)
				(type default)
			)
			(fill no)
			(layer "B.CrtYd")
		)
		(fp_rect
			(start 0.381 0.8382)
			(end -0.381 -0.8382)
			(stroke
				(width 0)
				(type default)
			)
			(fill no)
			(layer "B.Fab")
		)
		(pad "1" smd custom
			(at 0 -0.4318 270)
			(size 0.127 0.127)
			(layers "B.Cu" "B.Mask" "B.Paste")
			(net "P3V3")
			(options
				(clearance outline)
				(anchor circle)
			)
			(primitives
				(gr_poly
					(pts
						(arc
							(start -0.2032 0.2794)
							(mid -0.239121 0.264521)
							(end -0.254 0.2286)
						)
						(arc
							(start -0.254 -0.2286)
							(mid -0.239121 -0.264521)
							(end -0.2032 -0.2794)
						)
						(arc
							(start 0.2032 -0.2794)
							(mid 0.239121 -0.264521)
							(end 0.254 -0.2286)
						)
						(arc
							(start 0.254 0.2286)
							(mid 0.239121 0.264521)
							(end 0.2032 0.2794)
						)
					)
					(width 0)
					(fill yes)
				)
			)
		)
		(pad "2" smd custom
			(at 0 0.4318 270)
			(size 0.127 0.127)
			(layers "B.Cu" "B.Mask" "B.Paste")
			(net "SMBUS_HOST_ALRT#")
			(options
				(clearance outline)
				(anchor circle)
			)
			(primitives
				(gr_poly
					(pts
						(arc
							(start -0.2032 0.2794)
							(mid -0.239121 0.264521)
							(end -0.254 0.2286)
						)
						(arc
							(start -0.254 -0.2286)
							(mid -0.239121 -0.264521)
							(end -0.2032 -0.2794)
						)
						(arc
							(start 0.2032 -0.2794)
							(mid 0.239121 -0.264521)
							(end 0.254 -0.2286)
						)
						(arc
							(start 0.254 0.2286)
							(mid 0.239121 0.264521)
							(end 0.2032 0.2794)
						)
					)
					(width 0)
					(fill yes)
				)
			)
		)
	)
	(footprint ""
		(layer "B.Cu")
		(at 15.621 -68.7324)
		(property "Reference" "R505"
			(at 0 0 0)
			(layer "B.SilkS")
			(hide yes)
			(effects
				(font
					(size 1.27 1.27)
				)
				(justify mirror)
			)
		)
		(property "Value" "4K7R2F-GP"
			(at -1.7907 -1.1176 0)
			(unlocked yes)
			(layer "B.Fab")
			(hide yes)
			(effects
				(font
					(size 1.016 1.016)
					(thickness 0.1524)
				)
				(justify mirror)
			)
		)
		(property "Device Type" "R402H16"
			(at -1.7907 -2.6416 0)
			(unlocked yes)
			(layer "B.Fab")
			(hide yes)
			(effects
				(font
					(size 1.016 1.016)
					(thickness 0.1524)
				)
				(justify mirror)
			)
		)
		(duplicate_pad_numbers_are_jumpers no)
		(fp_rect
			(start 0.381 0.8382)
			(end -0.381 -0.8382)
			(stroke
				(width 0)
				(type default)
			)
			(fill no)
			(layer "B.CrtYd")
		)
		(fp_rect
			(start 0.381 0.8382)
			(end -0.381 -0.8382)
			(stroke
				(width 0)
				(type default)
			)
			(fill no)
			(layer "B.Fab")
		)
		(pad "1" smd custom
			(at 0 -0.4318 180)
			(size 0.127 0.127)
			(layers "B.Cu" "B.Mask" "B.Paste")
			(net "LED_NGFF_DAS")
			(options
				(clearance outline)
				(anchor circle)
			)
			(primitives
				(gr_poly
					(pts
						(arc
							(start -0.2032 0.2794)
							(mid -0.239121 0.264521)
							(end -0.254 0.2286)
						)
						(arc
							(start -0.254 -0.2286)
							(mid -0.239121 -0.264521)
							(end -0.2032 -0.2794)
						)
						(arc
							(start 0.2032 -0.2794)
							(mid 0.239121 -0.264521)
							(end 0.254 -0.2286)
						)
						(arc
							(start 0.254 0.2286)
							(mid 0.239121 0.264521)
							(end 0.2032 0.2794)
						)
					)
					(width 0)
					(fill yes)
				)
			)
		)
		(pad "2" smd custom
			(at 0 0.4318 180)
			(size 0.127 0.127)
			(layers "B.Cu" "B.Mask" "B.Paste")
			(net "GND")
			(options
				(clearance outline)
				(anchor circle)
			)
			(primitives
				(gr_poly
					(pts
						(arc
							(start -0.2032 0.2794)
							(mid -0.239121 0.264521)
							(end -0.254 0.2286)
						)
						(arc
							(start -0.254 -0.2286)
							(mid -0.239121 -0.264521)
							(end -0.2032 -0.2794)
						)
						(arc
							(start 0.2032 -0.2794)
							(mid 0.239121 -0.264521)
							(end 0.254 -0.2286)
						)
						(arc
							(start 0.254 0.2286)
							(mid 0.239121 0.264521)
							(end 0.2032 0.2794)
						)
					)
					(width 0)
					(fill yes)
				)
			)
		)
	)
	(footprint ""
		(layer "B.Cu")
		(at 33.4772 -12.7)
		(property "Reference" "C269"
			(at 0 0 0)
			(layer "B.SilkS")
			(hide yes)
			(effects
				(font
					(size 1.27 1.27)
				)
				(justify mirror)
			)
		)
		(property "Value" "SCD1U16V2KX-3GP"
			(at -1.1811 -2.7051 0)
			(unlocked yes)
			(layer "B.Fab")
			(hide yes)
			(effects
				(font
					(size 1.016 1.016)
					(thickness 0.1524)
				)
				(justify mirror)
			)
		)
		(property "Device Type" "C402H22"
			(at -1.1811 -4.2291 0)
			(unlocked yes)
			(layer "B.Fab")
			(hide yes)
			(effects
				(font
					(size 1.016 1.016)
					(thickness 0.1524)
				)
				(justify mirror)
			)
		)
		(duplicate_pad_numbers_are_jumpers no)
		(fp_rect
			(start 0.381 0.7366)
			(end -0.381 -0.7366)
			(stroke
				(width 0)
				(type default)
			)
			(fill no)
			(layer "B.CrtYd")
		)
		(fp_rect
			(start 0.381 0.7366)
			(end -0.381 -0.7366)
			(stroke
				(width 0)
				(type default)
			)
			(fill no)
			(layer "B.Fab")
		)
		(pad "1" smd custom
			(at 0 -0.4572 180)
			(size 0.1143 0.1143)
			(layers "B.Cu" "B.Mask" "B.Paste")
			(net "P2E_CPU_SAS_C_TX_DN7")
			(options
				(clearance outline)
				(anchor circle)
			)
			(primitives
				(gr_poly
					(pts
						(arc
							(start -0.254 0.1778)
							(mid -0.239121 0.213721)
							(end -0.2032 0.2286)
						)
						(arc
							(start 0.2032 0.2286)
							(mid 0.239121 0.213721)
							(end 0.254 0.1778)
						)
						(arc
							(start 0.254 -0.1778)
							(mid 0.239121 -0.213721)
							(end 0.2032 -0.2286)
						)
						(arc
							(start -0.2032 -0.2286)
							(mid -0.239121 -0.213721)
							(end -0.254 -0.1778)
						)
					)
					(width 0)
					(fill yes)
				)
			)
		)
		(pad "2" smd custom
			(at 0 0.4572 180)
			(size 0.1143 0.1143)
			(layers "B.Cu" "B.Mask" "B.Paste")
			(net "P2E_CPU_SAS_TX_DN7")
			(options
				(clearance outline)
				(anchor circle)
			)
			(primitives
				(gr_poly
					(pts
						(arc
							(start -0.254 0.1778)
							(mid -0.239121 0.213721)
							(end -0.2032 0.2286)
						)
						(arc
							(start 0.2032 0.2286)
							(mid 0.239121 0.213721)
							(end 0.254 0.1778)
						)
						(arc
							(start 0.254 -0.1778)
							(mid 0.239121 -0.213721)
							(end 0.2032 -0.2286)
						)
						(arc
							(start -0.2032 -0.2286)
							(mid -0.239121 -0.213721)
							(end -0.254 -0.1778)
						)
					)
					(width 0)
					(fill yes)
				)
			)
		)
	)
	(footprint ""
		(layer "B.Cu")
		(at 200.787 -25.654 -90)
		(property "Reference" "PC84"
			(at 0 0 90)
			(layer "B.SilkS")
			(hide yes)
			(effects
				(font
					(size 1.27 1.27)
				)
				(justify mirror)
			)
		)
		(property "Value" "SC22U25V5MX-GP"
			(at 0 -4.9022 270)
			(unlocked yes)
			(layer "B.Fab")
			(hide yes)
			(effects
				(font
					(size 1.016 1.016)
					(thickness 0.1524)
				)
				(justify mirror)
			)
		)
		(property "Device Type" "C805H58"
			(at 0 -6.8072 270)
			(unlocked yes)
			(layer "B.Fab")
			(hide yes)
			(effects
				(font
					(size 1.016 1.016)
					(thickness 0.1524)
				)
				(justify mirror)
			)
		)
		(duplicate_pad_numbers_are_jumpers no)
		(fp_line
			(start -0.6096 0)
			(end 0.6096 0)
			(stroke
				(width 0.3048)
				(type default)
			)
			(layer "B.SilkS")
		)
		(fp_poly
			(pts
				(xy 0.9017 1.4351) (xy -0.9017 1.4351) (xy -0.9017 -1.4351) (xy 0.9017 -1.4351)
			)
			(stroke
				(width 0)
				(type default)
			)
			(fill no)
			(layer "B.CrtYd")
		)
		(fp_poly
			(pts
				(xy -0.9017 1.4351) (xy -0.9017 -1.4351) (xy 0.9017 -1.4351) (xy 0.9017 1.4351)
			)
			(stroke
				(width 0)
				(type default)
			)
			(fill no)
			(layer "B.Fab")
		)
		(pad "1" smd rect
			(at 0 -0.8382 90)
			(size 1.5494 0.9398)
			(layers "B.Cu" "B.Mask" "B.Paste")
			(net "PVDDR_VIN")
		)
		(pad "2" smd rect
			(at 0 0.8382 90)
			(size 1.5494 0.9398)
			(layers "B.Cu" "B.Mask" "B.Paste")
			(net "GND")
		)
	)
	(footprint ""
		(layer "B.Cu")
		(at 72.3138 -33.655 -90)
		(property "Reference" "R329"
			(at 0 0 90)
			(layer "B.SilkS")
			(hide yes)
			(effects
				(font
					(size 1.27 1.27)
				)
				(justify mirror)
			)
		)
		(property "Value" "0R2J-2-GP"
			(at -0.064008 -3.993896 270)
			(unlocked yes)
			(layer "B.Fab")
			(hide yes)
			(effects
				(font
					(size 1.016 1.016)
					(thickness 0.1524)
				)
				(justify mirror)
			)
		)
		(property "Device Type" "R402H16"
			(at -0.064008 -5.517896 270)
			(unlocked yes)
			(layer "B.Fab")
			(hide yes)
			(effects
				(font
					(size 1.016 1.016)
					(thickness 0.1524)
				)
				(justify mirror)
			)
		)
		(duplicate_pad_numbers_are_jumpers no)
		(fp_rect
			(start 0.381 0.8382)
			(end -0.381 -0.8382)
			(stroke
				(width 0)
				(type default)
			)
			(fill no)
			(layer "B.CrtYd")
		)
		(fp_rect
			(start 0.381 0.8382)
			(end -0.381 -0.8382)
			(stroke
				(width 0)
				(type default)
			)
			(fill no)
			(layer "B.Fab")
		)
		(pad "1" smd custom
			(at 0 -0.4318 90)
			(size 0.127 0.127)
			(layers "B.Cu" "B.Mask" "B.Paste")
			(net "SRTCRST_R#")
			(options
				(clearance outline)
				(anchor circle)
			)
			(primitives
				(gr_poly
					(pts
						(arc
							(start -0.2032 0.2794)
							(mid -0.239121 0.264521)
							(end -0.254 0.2286)
						)
						(arc
							(start -0.254 -0.2286)
							(mid -0.239121 -0.264521)
							(end -0.2032 -0.2794)
						)
						(arc
							(start 0.2032 -0.2794)
							(mid 0.239121 -0.264521)
							(end 0.254 -0.2286)
						)
						(arc
							(start 0.254 0.2286)
							(mid 0.239121 0.264521)
							(end 0.2032 0.2794)
						)
					)
					(width 0)
					(fill yes)
				)
			)
		)
		(pad "2" smd custom
			(at 0 0.4318 90)
			(size 0.127 0.127)
			(layers "B.Cu" "B.Mask" "B.Paste")
			(net "SRTCRST#")
			(options
				(clearance outline)
				(anchor circle)
			)
			(primitives
				(gr_poly
					(pts
						(arc
							(start -0.2032 0.2794)
							(mid -0.239121 0.264521)
							(end -0.254 0.2286)
						)
						(arc
							(start -0.254 -0.2286)
							(mid -0.239121 -0.264521)
							(end -0.2032 -0.2794)
						)
						(arc
							(start 0.2032 -0.2794)
							(mid 0.239121 -0.264521)
							(end 0.254 -0.2286)
						)
						(arc
							(start 0.254 0.2286)
							(mid 0.239121 0.264521)
							(end 0.2032 0.2794)
						)
					)
					(width 0)
					(fill yes)
				)
			)
		)
	)
	(footprint ""
		(layer "B.Cu")
		(at 197.993 -41.91 -90)
		(property "Reference" "R154"
			(at 0 0 90)
			(layer "B.SilkS")
			(hide yes)
			(effects
				(font
					(size 1.27 1.27)
				)
				(justify mirror)
			)
		)
		(property "Value" "300R2F-GP"
			(at -0.064008 -3.993896 270)
			(unlocked yes)
			(layer "B.Fab")
			(hide yes)
			(effects
				(font
					(size 1.016 1.016)
					(thickness 0.1524)
				)
				(justify mirror)
			)
		)
		(property "Device Type" "R402H16"
			(at -0.064008 -5.517896 270)
			(unlocked yes)
			(layer "B.Fab")
			(hide yes)
			(effects
				(font
					(size 1.016 1.016)
					(thickness 0.1524)
				)
				(justify mirror)
			)
		)
		(duplicate_pad_numbers_are_jumpers no)
		(fp_rect
			(start 0.381 0.8382)
			(end -0.381 -0.8382)
			(stroke
				(width 0)
				(type default)
			)
			(fill no)
			(layer "B.CrtYd")
		)
		(fp_rect
			(start 0.381 0.8382)
			(end -0.381 -0.8382)
			(stroke
				(width 0)
				(type default)
			)
			(fill no)
			(layer "B.Fab")
		)
		(pad "1" smd custom
			(at 0 -0.4318 90)
			(size 0.127 0.127)
			(layers "B.Cu" "B.Mask" "B.Paste")
			(net "PORT80_R_BIT5")
			(options
				(clearance outline)
				(anchor circle)
			)
			(primitives
				(gr_poly
					(pts
						(arc
							(start -0.2032 0.2794)
							(mid -0.239121 0.264521)
							(end -0.254 0.2286)
						)
						(arc
							(start -0.254 -0.2286)
							(mid -0.239121 -0.264521)
							(end -0.2032 -0.2794)
						)
						(arc
							(start 0.2032 -0.2794)
							(mid 0.239121 -0.264521)
							(end 0.254 -0.2286)
						)
						(arc
							(start 0.254 0.2286)
							(mid 0.239121 0.264521)
							(end 0.2032 0.2794)
						)
					)
					(width 0)
					(fill yes)
				)
			)
		)
		(pad "2" smd custom
			(at 0 0.4318 90)
			(size 0.127 0.127)
			(layers "B.Cu" "B.Mask" "B.Paste")
			(net "P3V3_STBY")
			(options
				(clearance outline)
				(anchor circle)
			)
			(primitives
				(gr_poly
					(pts
						(arc
							(start -0.2032 0.2794)
							(mid -0.239121 0.264521)
							(end -0.254 0.2286)
						)
						(arc
							(start -0.254 -0.2286)
							(mid -0.239121 -0.264521)
							(end -0.2032 -0.2794)
						)
						(arc
							(start 0.2032 -0.2794)
							(mid 0.239121 -0.264521)
							(end 0.254 -0.2286)
						)
						(arc
							(start 0.254 0.2286)
							(mid 0.239121 0.264521)
							(end 0.2032 0.2794)
						)
					)
					(width 0)
					(fill yes)
				)
			)
		)
	)
	(footprint ""
		(layer "B.Cu")
		(at 151.384 -59.309)
		(property "Reference" "C100"
			(at 0 0 0)
			(layer "B.SilkS")
			(hide yes)
			(effects
				(font
					(size 1.27 1.27)
				)
				(justify mirror)
			)
		)
		(property "Value" "SC10U6D3V3MX-GP"
			(at 0.0254 -2.0193 0)
			(unlocked yes)
			(layer "B.Fab")
			(hide yes)
			(effects
				(font
					(size 1.016 1.016)
					(thickness 0.1524)
				)
				(justify mirror)
			)
		)
		(property "Device Type" "C603H38"
			(at 0.0254 -3.5433 0)
			(unlocked yes)
			(layer "B.Fab")
			(hide yes)
			(effects
				(font
					(size 1.016 1.016)
					(thickness 0.1524)
				)
				(justify mirror)
			)
		)
		(duplicate_pad_numbers_are_jumpers no)
		(fp_line
			(start 0.4064 0)
			(end -0.4064 0)
			(stroke
				(width 0.2286)
				(type default)
			)
			(layer "B.SilkS")
		)
		(fp_rect
			(start 0.635 1.1811)
			(end -0.635 -1.1811)
			(stroke
				(width 0)
				(type default)
			)
			(fill no)
			(layer "B.CrtYd")
		)
		(fp_rect
			(start 0.635 1.1811)
			(end -0.635 -1.1811)
			(stroke
				(width 0)
				(type default)
			)
			(fill no)
			(layer "B.Fab")
		)
		(pad "1" smd custom
			(at 0 -0.6604 180)
			(size 0.19685 0.19685)
			(layers "B.Cu" "B.Mask" "B.Paste")
			(net "PV_VDDR")
			(options
				(clearance outline)
				(anchor circle)
			)
			(primitives
				(gr_poly
					(pts
						(arc
							(start 0.508 0.2921)
							(mid 0.478242 0.363942)
							(end 0.4064 0.3937)
						)
						(arc
							(start -0.4064 0.3937)
							(mid -0.478242 0.363942)
							(end -0.508 0.2921)
						)
						(arc
							(start -0.508 -0.2921)
							(mid -0.478242 -0.363942)
							(end -0.4064 -0.3937)
						)
						(arc
							(start 0.4064 -0.3937)
							(mid 0.478242 -0.363942)
							(end 0.508 -0.2921)
						)
					)
					(width 0)
					(fill yes)
				)
			)
		)
		(pad "2" smd custom
			(at 0 0.6604 180)
			(size 0.19685 0.19685)
			(layers "B.Cu" "B.Mask" "B.Paste")
			(net "GND")
			(options
				(clearance outline)
				(anchor circle)
			)
			(primitives
				(gr_poly
					(pts
						(arc
							(start 0.508 0.2921)
							(mid 0.478242 0.363942)
							(end 0.4064 0.3937)
						)
						(arc
							(start -0.4064 0.3937)
							(mid -0.478242 0.363942)
							(end -0.508 0.2921)
						)
						(arc
							(start -0.508 -0.2921)
							(mid -0.478242 -0.363942)
							(end -0.4064 -0.3937)
						)
						(arc
							(start 0.4064 -0.3937)
							(mid 0.478242 -0.363942)
							(end 0.508 -0.2921)
						)
					)
					(width 0)
					(fill yes)
				)
			)
		)
	)
	(footprint ""
		(layer "B.Cu")
		(at 82.423 -24.511)
		(property "Reference" "R304"
			(at 0 0 0)
			(layer "B.SilkS")
			(hide yes)
			(effects
				(font
					(size 1.27 1.27)
				)
				(justify mirror)
			)
		)
		(property "Value" "0R2J-2-GP"
			(at -0.064008 -3.993896 0)
			(unlocked yes)
			(layer "B.Fab")
			(hide yes)
			(effects
				(font
					(size 1.016 1.016)
					(thickness 0.1524)
				)
				(justify mirror)
			)
		)
		(property "Device Type" "R402H16"
			(at -0.064008 -5.517896 0)
			(unlocked yes)
			(layer "B.Fab")
			(hide yes)
			(effects
				(font
					(size 1.016 1.016)
					(thickness 0.1524)
				)
				(justify mirror)
			)
		)
		(duplicate_pad_numbers_are_jumpers no)
		(fp_rect
			(start 0.381 0.8382)
			(end -0.381 -0.8382)
			(stroke
				(width 0)
				(type default)
			)
			(fill no)
			(layer "B.CrtYd")
		)
		(fp_rect
			(start 0.381 0.8382)
			(end -0.381 -0.8382)
			(stroke
				(width 0)
				(type default)
			)
			(fill no)
			(layer "B.Fab")
		)
		(pad "1" smd custom
			(at 0 -0.4318 180)
			(size 0.127 0.127)
			(layers "B.Cu" "B.Mask" "B.Paste")
			(net "CPU_UART_RXD_R")
			(options
				(clearance outline)
				(anchor circle)
			)
			(primitives
				(gr_poly
					(pts
						(arc
							(start -0.2032 0.2794)
							(mid -0.239121 0.264521)
							(end -0.254 0.2286)
						)
						(arc
							(start -0.254 -0.2286)
							(mid -0.239121 -0.264521)
							(end -0.2032 -0.2794)
						)
						(arc
							(start 0.2032 -0.2794)
							(mid 0.239121 -0.264521)
							(end 0.254 -0.2286)
						)
						(arc
							(start 0.254 0.2286)
							(mid 0.239121 0.264521)
							(end 0.2032 0.2794)
						)
					)
					(width 0)
					(fill yes)
				)
			)
		)
		(pad "2" smd custom
			(at 0 0.4318 180)
			(size 0.127 0.127)
			(layers "B.Cu" "B.Mask" "B.Paste")
			(net "CPU_RXD")
			(options
				(clearance outline)
				(anchor circle)
			)
			(primitives
				(gr_poly
					(pts
						(arc
							(start -0.2032 0.2794)
							(mid -0.239121 0.264521)
							(end -0.254 0.2286)
						)
						(arc
							(start -0.254 -0.2286)
							(mid -0.239121 -0.264521)
							(end -0.2032 -0.2794)
						)
						(arc
							(start 0.2032 -0.2794)
							(mid 0.239121 -0.264521)
							(end 0.254 -0.2286)
						)
						(arc
							(start 0.254 0.2286)
							(mid 0.239121 0.264521)
							(end 0.2032 0.2794)
						)
					)
					(width 0)
					(fill yes)
				)
			)
		)
	)
)
